(kicad_pcb
	(version 20260206)
	(generator "pcbnew")
	(generator_version "10.0")
	(general
		(thickness 1.6)
		(legacy_teardrops no)
	)
	(paper "A4")
	(title_block
		(title "01162023_DA0F0TEBIF0_F0T_Expander_BD_F_brd_V02_OCP.brd")
		(comment 1 "Grand Teton / footprints 5302-5308 of 9728")
	)
	(layers
		(0 "F.Cu" signal "TOP")
		(4 "In1.Cu" signal "GND")
		(6 "In2.Cu" signal "VCC")
		(8 "In3.Cu" signal "VCC1")
		(10 "In4.Cu" signal "GND1")
		(12 "In5.Cu" signal "IN1")
		(14 "In6.Cu" signal "GND2")
		(16 "In7.Cu" signal "IN2")
		(18 "In8.Cu" signal "GND3")
		(20 "In9.Cu" signal "IN3")
		(22 "In10.Cu" signal "GND4")
		(24 "In11.Cu" signal "IN4")
		(26 "In12.Cu" signal "GND5")
		(28 "In13.Cu" signal "IN5")
		(30 "In14.Cu" signal "GND6")
		(32 "In15.Cu" signal "IN6")
		(34 "In16.Cu" signal "GND7")
		(2 "B.Cu" signal "BOTTOM")
		(9 "F.Adhes" user "F.Adhesive")
		(11 "B.Adhes" user "B.Adhesive")
		(13 "F.Paste" user "Package Geometry/Pastemask Top")
		(15 "B.Paste" user "Package Geometry/Pastemask Bottom")
		(5 "F.SilkS" user "Ref Des/Silkscreen Top")
		(7 "B.SilkS" user "Ref Des/Silkscreen Bottom")
		(1 "F.Mask" user "Board Geometry/Soldermask Top")
		(3 "B.Mask" user "Board Geometry/Soldermask Bottom")
		(17 "Dwgs.User" user "User.Drawings")
		(19 "Cmts.User" user "User.Comments")
		(21 "Eco1.User" user "User.Eco1")
		(23 "Eco2.User" user "User.Eco2")
		(25 "Edge.Cuts" user "Board Geometry/Outline")
		(27 "Margin" user)
		(31 "F.CrtYd" user "Package Geometry/Place Bound Top")
		(29 "B.CrtYd" user "Package Geometry/Place Bound Bottom")
		(35 "F.Fab" user "Ref Des/Assembly Top")
		(33 "B.Fab" user "Ref Des/Assembly Bottom")
	)
	(footprint ""
		(layer "F.Cu")
		(at 421.8305 -66.32194 -90)
		(property "Reference" "PC895"
			(at 0 0 270)
			(layer "F.SilkS")
			(hide yes)
			(effects
				(font
					(size 1.27 1.27)
				)
			)
		)
		(property "Value" ""
			(at 0 0 270)
			(layer "F.Fab")
			(effects
				(font
					(size 1.27 1.27)
				)
			)
		)
		(duplicate_pad_numbers_are_jumpers no)
		(fp_line
			(start -0.7874 0.4064)
			(end -0.7874 -0.4064)
			(stroke
				(width 0.1524)
				(type default)
			)
			(layer "F.SilkS")
		)
		(fp_line
			(start 0.7874 0.4064)
			(end -0.7874 0.4064)
			(stroke
				(width 0.1524)
				(type default)
			)
			(layer "F.SilkS")
		)
		(fp_line
			(start -0.7874 -0.4064)
			(end 0.7874 -0.4064)
			(stroke
				(width 0.1524)
				(type default)
			)
			(layer "F.SilkS")
		)
		(fp_line
			(start 0.7874 -0.4064)
			(end 0.7874 0.4064)
			(stroke
				(width 0.1524)
				(type default)
			)
			(layer "F.SilkS")
		)
		(fp_line
			(start -0.67945 0.3048)
			(end -0.67945 -0.305054)
			(stroke
				(width 0.1)
				(type default)
			)
			(layer "F.Fab")
		)
		(fp_line
			(start -0.12065 0.3048)
			(end -0.67945 0.3048)
			(stroke
				(width 0.1)
				(type default)
			)
			(layer "F.Fab")
		)
		(fp_line
			(start 0.120396 0.3048)
			(end 0.120396 0.2794)
			(stroke
				(width 0.1)
				(type default)
			)
			(layer "F.Fab")
		)
		(fp_line
			(start 0.67945 0.3048)
			(end 0.120396 0.3048)
			(stroke
				(width 0.1)
				(type default)
			)
			(layer "F.Fab")
		)
		(fp_line
			(start -0.12065 0.2794)
			(end -0.12065 0.3048)
			(stroke
				(width 0.1)
				(type default)
			)
			(layer "F.Fab")
		)
		(fp_line
			(start 0.120396 0.2794)
			(end -0.12065 0.2794)
			(stroke
				(width 0.1)
				(type default)
			)
			(layer "F.Fab")
		)
		(fp_line
			(start -0.12065 -0.2794)
			(end 0.12065 -0.2794)
			(stroke
				(width 0.1)
				(type default)
			)
			(layer "F.Fab")
		)
		(fp_line
			(start 0.12065 -0.2794)
			(end 0.12065 -0.3048)
			(stroke
				(width 0.1)
				(type default)
			)
			(layer "F.Fab")
		)
		(fp_line
			(start 0.12065 -0.3048)
			(end 0.67945 -0.3048)
			(stroke
				(width 0.1)
				(type default)
			)
			(layer "F.Fab")
		)
		(fp_line
			(start 0.67945 -0.3048)
			(end 0.67945 0.3048)
			(stroke
				(width 0.1)
				(type default)
			)
			(layer "F.Fab")
		)
		(fp_line
			(start -0.67945 -0.305054)
			(end -0.12065 -0.305054)
			(stroke
				(width 0.1)
				(type default)
			)
			(layer "F.Fab")
		)
		(fp_line
			(start -0.12065 -0.305054)
			(end -0.12065 -0.2794)
			(stroke
				(width 0.1)
				(type default)
			)
			(layer "F.Fab")
		)
		(pad "1" smd circle
			(at -0.40005 0 270)
			(size 0 0)
			(layers "F.Cu" "F.Mask" "F.Paste")
			(net "P12V_SSD14_CO_DV_DT")
		)
		(pad "2" smd circle
			(at 0.40005 0 270)
			(size 0 0)
			(layers "F.Cu" "F.Mask" "F.Paste")
			(net "GND")
		)
	)
	(footprint ""
		(layer "F.Cu")
		(at 331.131164 -343.952322 90)
		(property "Reference" "C567"
			(at 0 0 90)
			(layer "F.SilkS")
			(hide yes)
			(effects
				(font
					(size 1.27 1.27)
				)
			)
		)
		(property "Value" ""
			(at 0 0 90)
			(layer "F.Fab")
			(effects
				(font
					(size 1.27 1.27)
				)
			)
		)
		(duplicate_pad_numbers_are_jumpers no)
		(fp_line
			(start 0.299974 -0.150114)
			(end 0.299974 0.150114)
			(stroke
				(width 0.1)
				(type default)
			)
			(layer "F.Fab")
		)
		(fp_line
			(start -0.299974 -0.150114)
			(end 0.299974 -0.150114)
			(stroke
				(width 0.1)
				(type default)
			)
			(layer "F.Fab")
		)
		(fp_line
			(start 0.299974 0.150114)
			(end -0.299974 0.150114)
			(stroke
				(width 0.1)
				(type default)
			)
			(layer "F.Fab")
		)
		(fp_line
			(start -0.299974 0.150114)
			(end -0.299974 -0.150114)
			(stroke
				(width 0.1)
				(type default)
			)
			(layer "F.Fab")
		)
		(pad "1" smd rect
			(at -0.2667 0 90)
			(size 0.3048 0.381)
			(layers "F.Cu" "F.Mask" "F.Paste")
			(net "P5E_PEX2_STN6_TX_DP<103>")
		)
		(pad "2" smd rect
			(at 0.2667 0 90)
			(size 0.3048 0.381)
			(layers "F.Cu" "F.Mask" "F.Paste")
			(net "P5E_PEX2_STN6_TX_C_DP<103>")
		)
	)
	(footprint ""
		(layer "F.Cu")
		(at 208.638648 -121.528332 90)
		(property "Reference" "PC488"
			(at 0 0 90)
			(layer "F.SilkS")
			(hide yes)
			(effects
				(font
					(size 1.27 1.27)
				)
			)
		)
		(property "Value" ""
			(at 0 0 90)
			(layer "F.Fab")
			(effects
				(font
					(size 1.27 1.27)
				)
			)
		)
		(duplicate_pad_numbers_are_jumpers no)
		(fp_line
			(start 0.7874 -0.4064)
			(end 0.7874 0.4064)
			(stroke
				(width 0.1524)
				(type default)
			)
			(layer "F.SilkS")
		)
		(fp_line
			(start -0.7874 -0.4064)
			(end 0.7874 -0.4064)
			(stroke
				(width 0.1524)
				(type default)
			)
			(layer "F.SilkS")
		)
		(fp_line
			(start 0.7874 0.4064)
			(end -0.7874 0.4064)
			(stroke
				(width 0.1524)
				(type default)
			)
			(layer "F.SilkS")
		)
		(fp_line
			(start -0.7874 0.4064)
			(end -0.7874 -0.4064)
			(stroke
				(width 0.1524)
				(type default)
			)
			(layer "F.SilkS")
		)
		(fp_line
			(start -0.12065 -0.305054)
			(end -0.12065 -0.2794)
			(stroke
				(width 0.1)
				(type default)
			)
			(layer "F.Fab")
		)
		(fp_line
			(start -0.67945 -0.305054)
			(end -0.12065 -0.305054)
			(stroke
				(width 0.1)
				(type default)
			)
			(layer "F.Fab")
		)
		(fp_line
			(start 0.67945 -0.3048)
			(end 0.67945 0.3048)
			(stroke
				(width 0.1)
				(type default)
			)
			(layer "F.Fab")
		)
		(fp_line
			(start 0.12065 -0.3048)
			(end 0.67945 -0.3048)
			(stroke
				(width 0.1)
				(type default)
			)
			(layer "F.Fab")
		)
		(fp_line
			(start 0.12065 -0.2794)
			(end 0.12065 -0.3048)
			(stroke
				(width 0.1)
				(type default)
			)
			(layer "F.Fab")
		)
		(fp_line
			(start -0.12065 -0.2794)
			(end 0.12065 -0.2794)
			(stroke
				(width 0.1)
				(type default)
			)
			(layer "F.Fab")
		)
		(fp_line
			(start 0.120396 0.2794)
			(end -0.12065 0.2794)
			(stroke
				(width 0.1)
				(type default)
			)
			(layer "F.Fab")
		)
		(fp_line
			(start -0.12065 0.2794)
			(end -0.12065 0.3048)
			(stroke
				(width 0.1)
				(type default)
			)
			(layer "F.Fab")
		)
		(fp_line
			(start 0.67945 0.3048)
			(end 0.120396 0.3048)
			(stroke
				(width 0.1)
				(type default)
			)
			(layer "F.Fab")
		)
		(fp_line
			(start 0.120396 0.3048)
			(end 0.120396 0.2794)
			(stroke
				(width 0.1)
				(type default)
			)
			(layer "F.Fab")
		)
		(fp_line
			(start -0.12065 0.3048)
			(end -0.67945 0.3048)
			(stroke
				(width 0.1)
				(type default)
			)
			(layer "F.Fab")
		)
		(fp_line
			(start -0.67945 0.3048)
			(end -0.67945 -0.305054)
			(stroke
				(width 0.1)
				(type default)
			)
			(layer "F.Fab")
		)
		(pad "1" smd circle
			(at -0.40005 0 90)
			(size 0 0)
			(layers "F.Cu" "F.Mask" "F.Paste")
			(net "P3V3_NIC3")
		)
		(pad "2" smd circle
			(at 0.40005 0 90)
			(size 0 0)
			(layers "F.Cu" "F.Mask" "F.Paste")
			(net "GND")
		)
	)
	(footprint ""
		(layer "F.Cu")
		(at 342.214962 -17.999964)
		(property "Reference" "H54"
			(at -4.629912 -4.985512 0)
			(unlocked yes)
			(layer "F.SilkS")
			(effects
				(font
					(size 0.7874 0.5842)
					(thickness 0.1524)
				)
				(justify left)
			)
		)
		(property "Value" ""
			(at 0 0 0)
			(layer "F.Fab")
			(effects
				(font
					(size 1.27 1.27)
				)
			)
		)
		(duplicate_pad_numbers_are_jumpers no)
		(pad "1" thru_hole circle
			(at 0 0)
			(size 10.0076 10.0076)
			(drill 5.6134)
			(layers "*.Cu" "*.Mask")
			(remove_unused_layers no)
			(net "GND")
			(clearance -1.9431)
		)
	)
	(footprint ""
		(layer "F.Cu")
		(at 89.005156 -298.87291 -90)
		(property "Reference" "R3885"
			(at 0 0 270)
			(layer "F.SilkS")
			(hide yes)
			(effects
				(font
					(size 1.27 1.27)
				)
			)
		)
		(property "Value" ""
			(at 0 0 270)
			(layer "F.Fab")
			(effects
				(font
					(size 1.27 1.27)
				)
			)
		)
		(duplicate_pad_numbers_are_jumpers no)
		(fp_line
			(start -0.7874 0.4064)
			(end -0.7874 -0.4064)
			(stroke
				(width 0.1524)
				(type default)
			)
			(layer "F.SilkS")
		)
		(fp_line
			(start 0.7874 0.4064)
			(end -0.7874 0.4064)
			(stroke
				(width 0.1524)
				(type default)
			)
			(layer "F.SilkS")
		)
		(fp_line
			(start -0.7874 -0.4064)
			(end 0.7874 -0.4064)
			(stroke
				(width 0.1524)
				(type default)
			)
			(layer "F.SilkS")
		)
		(fp_line
			(start 0.7874 -0.4064)
			(end 0.7874 0.4064)
			(stroke
				(width 0.1524)
				(type default)
			)
			(layer "F.SilkS")
		)
		(fp_line
			(start -0.67945 0.3048)
			(end -0.67945 -0.305054)
			(stroke
				(width 0.1)
				(type default)
			)
			(layer "F.Fab")
		)
		(fp_line
			(start -0.12065 0.3048)
			(end -0.67945 0.3048)
			(stroke
				(width 0.1)
				(type default)
			)
			(layer "F.Fab")
		)
		(fp_line
			(start 0.120396 0.3048)
			(end 0.120396 0.2794)
			(stroke
				(width 0.1)
				(type default)
			)
			(layer "F.Fab")
		)
		(fp_line
			(start 0.67945 0.3048)
			(end 0.120396 0.3048)
			(stroke
				(width 0.1)
				(type default)
			)
			(layer "F.Fab")
		)
		(fp_line
			(start -0.12065 0.2794)
			(end -0.12065 0.3048)
			(stroke
				(width 0.1)
				(type default)
			)
			(layer "F.Fab")
		)
		(fp_line
			(start 0.120396 0.2794)
			(end -0.12065 0.2794)
			(stroke
				(width 0.1)
				(type default)
			)
			(layer "F.Fab")
		)
		(fp_line
			(start -0.12065 -0.2794)
			(end 0.12065 -0.2794)
			(stroke
				(width 0.1)
				(type default)
			)
			(layer "F.Fab")
		)
		(fp_line
			(start 0.12065 -0.2794)
			(end 0.12065 -0.3048)
			(stroke
				(width 0.1)
				(type default)
			)
			(layer "F.Fab")
		)
		(fp_line
			(start 0.12065 -0.3048)
			(end 0.67945 -0.3048)
			(stroke
				(width 0.1)
				(type default)
			)
			(layer "F.Fab")
		)
		(fp_line
			(start 0.67945 -0.3048)
			(end 0.67945 0.3048)
			(stroke
				(width 0.1)
				(type default)
			)
			(layer "F.Fab")
		)
		(fp_line
			(start -0.67945 -0.305054)
			(end -0.12065 -0.305054)
			(stroke
				(width 0.1)
				(type default)
			)
			(layer "F.Fab")
		)
		(fp_line
			(start -0.12065 -0.305054)
			(end -0.12065 -0.2794)
			(stroke
				(width 0.1)
				(type default)
			)
			(layer "F.Fab")
		)
		(pad "1" smd circle
			(at -0.40005 0 270)
			(size 0 0)
			(layers "F.Cu" "F.Mask" "F.Paste")
			(net "I2C_PEX0_HOST_SDA")
		)
		(pad "2" smd circle
			(at 0.40005 0 270)
			(size 0 0)
			(layers "F.Cu" "F.Mask" "F.Paste")
			(net "I2C_PEX0_HOST_R_SDA")
		)
	)
	(footprint ""
		(layer "F.Cu")
		(at 19.062446 -212.631528 90)
		(property "Reference" "R6567"
			(at 0 0 90)
			(layer "F.SilkS")
			(hide yes)
			(effects
				(font
					(size 1.27 1.27)
				)
			)
		)
		(property "Value" ""
			(at 0 0 90)
			(layer "F.Fab")
			(effects
				(font
					(size 1.27 1.27)
				)
			)
		)
		(duplicate_pad_numbers_are_jumpers no)
		(fp_line
			(start 0.7874 -0.4064)
			(end 0.7874 0.4064)
			(stroke
				(width 0.1524)
				(type default)
			)
			(layer "F.SilkS")
		)
		(fp_line
			(start -0.7874 -0.4064)
			(end 0.7874 -0.4064)
			(stroke
				(width 0.1524)
				(type default)
			)
			(layer "F.SilkS")
		)
		(fp_line
			(start 0.7874 0.4064)
			(end -0.7874 0.4064)
			(stroke
				(width 0.1524)
				(type default)
			)
			(layer "F.SilkS")
		)
		(fp_line
			(start -0.7874 0.4064)
			(end -0.7874 -0.4064)
			(stroke
				(width 0.1524)
				(type default)
			)
			(layer "F.SilkS")
		)
		(fp_line
			(start -0.12065 -0.305054)
			(end -0.12065 -0.2794)
			(stroke
				(width 0.1)
				(type default)
			)
			(layer "F.Fab")
		)
		(fp_line
			(start -0.67945 -0.305054)
			(end -0.12065 -0.305054)
			(stroke
				(width 0.1)
				(type default)
			)
			(layer "F.Fab")
		)
		(fp_line
			(start 0.67945 -0.3048)
			(end 0.67945 0.3048)
			(stroke
				(width 0.1)
				(type default)
			)
			(layer "F.Fab")
		)
		(fp_line
			(start 0.12065 -0.3048)
			(end 0.67945 -0.3048)
			(stroke
				(width 0.1)
				(type default)
			)
			(layer "F.Fab")
		)
		(fp_line
			(start 0.12065 -0.2794)
			(end 0.12065 -0.3048)
			(stroke
				(width 0.1)
				(type default)
			)
			(layer "F.Fab")
		)
		(fp_line
			(start -0.12065 -0.2794)
			(end 0.12065 -0.2794)
			(stroke
				(width 0.1)
				(type default)
			)
			(layer "F.Fab")
		)
		(fp_line
			(start 0.120396 0.2794)
			(end -0.12065 0.2794)
			(stroke
				(width 0.1)
				(type default)
			)
			(layer "F.Fab")
		)
		(fp_line
			(start -0.12065 0.2794)
			(end -0.12065 0.3048)
			(stroke
				(width 0.1)
				(type default)
			)
			(layer "F.Fab")
		)
		(fp_line
			(start 0.67945 0.3048)
			(end 0.120396 0.3048)
			(stroke
				(width 0.1)
				(type default)
			)
			(layer "F.Fab")
		)
		(fp_line
			(start 0.120396 0.3048)
			(end 0.120396 0.2794)
			(stroke
				(width 0.1)
				(type default)
			)
			(layer "F.Fab")
		)
		(fp_line
			(start -0.12065 0.3048)
			(end -0.67945 0.3048)
			(stroke
				(width 0.1)
				(type default)
			)
			(layer "F.Fab")
		)
		(fp_line
			(start -0.67945 0.3048)
			(end -0.67945 -0.305054)
			(stroke
				(width 0.1)
				(type default)
			)
			(layer "F.Fab")
		)
		(pad "1" smd circle
			(at -0.40005 0 90)
			(size 0 0)
			(layers "F.Cu" "F.Mask" "F.Paste")
			(net "P1V8_PLL_PEX0_ADJ")
		)
		(pad "2" smd circle
			(at 0.40005 0 90)
			(size 0 0)
			(layers "F.Cu" "F.Mask" "F.Paste")
			(net "GND")
		)
	)
	(footprint ""
		(layer "F.Cu")
		(at 353.889564 -63.56223)
		(property "Reference" "Q208"
			(at 2.523236 -1.9177 0)
			(unlocked yes)
			(layer "F.SilkS")
			(effects
				(font
					(size 0.7874 0.5842)
					(thickness 0.1524)
				)
			)
		)
		(property "Value" ""
			(at 0 0 0)
			(layer "F.Fab")
			(effects
				(font
					(size 1.27 1.27)
				)
			)
		)
		(duplicate_pad_numbers_are_jumpers no)
		(fp_line
			(start -1.376172 -1.199896)
			(end -0.508 -1.199896)
			(stroke
				(width 0.1524)
				(type default)
			)
			(layer "F.SilkS")
		)
		(fp_line
			(start -1.376172 1.199896)
			(end -1.376172 -1.199896)
			(stroke
				(width 0.1524)
				(type default)
			)
			(layer "F.SilkS")
		)
		(fp_line
			(start -0.508 -1.199896)
			(end 0 -0.762)
			(stroke
				(width 0.1524)
				(type default)
			)
			(layer "F.SilkS")
		)
		(fp_line
			(start 0 -0.762)
			(end 0.508 -1.199896)
			(stroke
				(width 0.1524)
				(type default)
			)
			(layer "F.SilkS")
		)
		(fp_line
			(start 0.508 -1.199896)
			(end 1.376172 -1.199896)
			(stroke
				(width 0.1524)
				(type default)
			)
			(layer "F.SilkS")
		)
		(fp_line
			(start 1.376172 -1.199896)
			(end 1.376172 1.199896)
			(stroke
				(width 0.1524)
				(type default)
			)
			(layer "F.SilkS")
		)
		(fp_line
			(start 1.376172 1.199896)
			(end -1.376172 1.199896)
			(stroke
				(width 0.1524)
				(type default)
			)
			(layer "F.SilkS")
		)
		(fp_poly
			(pts
				(xy -1.421638 -0.804164) (xy -1.691132 -1.612392) (xy -2.229866 -1.073658)
			)
			(stroke
				(width 0)
				(type default)
			)
			(fill yes)
			(layer "F.SilkS")
		)
		(fp_line
			(start -0.674878 -1.100074)
			(end 0.674878 -1.100074)
			(stroke
				(width 0.1)
				(type default)
			)
			(layer "F.Fab")
		)
		(fp_line
			(start -0.674878 1.100074)
			(end -0.674878 -1.100074)
			(stroke
				(width 0.1)
				(type default)
			)
			(layer "F.Fab")
		)
		(fp_line
			(start 0.674878 -1.100074)
			(end 0.674878 1.100074)
			(stroke
				(width 0.1)
				(type default)
			)
			(layer "F.Fab")
		)
		(fp_line
			(start 0.674878 1.100074)
			(end -0.674878 1.100074)
			(stroke
				(width 0.1)
				(type default)
			)
			(layer "F.Fab")
		)
		(fp_poly
			(pts
				(xy -1.4605 -0.7493) (xy -2.2225 -1.1303) (xy -2.2225 -0.3683)
			)
			(stroke
				(width 0)
				(type default)
			)
			(fill yes)
			(layer "F.Fab")
		)
		(pad "1" smd rect
			(at -0.899922 -0.750062 270)
			(size 0.6096 0.6096)
			(layers "F.Cu" "F.Mask" "F.Paste")
			(net "GND")
		)
		(pad "2" smd rect
			(at -0.899922 0 270)
			(size 0.4064 0.6096)
			(layers "F.Cu" "F.Mask" "F.Paste")
			(net "P12V_SSD12_PG_G1")
		)
		(pad "3" smd rect
			(at -0.899922 0.750062 270)
			(size 0.6096 0.6096)
			(layers "F.Cu" "F.Mask" "F.Paste")
			(net "PWRGD_P12V_SSD12_D")
		)
		(pad "4" smd rect
			(at 0.899922 0.750062 270)
			(size 0.6096 0.6096)
			(layers "F.Cu" "F.Mask" "F.Paste")
			(net "GND")
		)
		(pad "5" smd rect
			(at 0.899922 0 270)
			(size 0.4064 0.6096)
			(layers "F.Cu" "F.Mask" "F.Paste")
			(net "P12V_SSD12_PG_G2")
		)
		(pad "6" smd rect
			(at 0.899922 -0.750062 270)
			(size 0.6096 0.6096)
			(layers "F.Cu" "F.Mask" "F.Paste")
			(net "P12V_SSD12_PG_G2")
		)
	)
)
